# T6G (Grand Teton) — schematic parts with pin connectivity, parts 2604–2604 of 8303; source: Cadence DE-HDL packaged netlist (pstxprt.dat, pstxnet.dat, pstchip.dat)

J23  SCONN288_DDR506112002KQ  IO  pkg DDR288S_1-1VXC  page 91
  1  VIN_BULK0  POWER  = P12V_MEM_CPU0
  2  RFU0  TRI  = NC
  3  VIN_MGMT  POWER  = P3V3_AUX
  4  HSCL  IN  = I3C_SPD_DDRF_CPU0_SCL
  5  HSDA  BI  = I3C_SPD_DDRF_CPU0_SDA
  6  VSS0  POWER  = GND
  7  DQ0_A  BI  = M_F_CPU0_SA_DQ<0>
  8  VSS1  POWER  = GND
  9  DQ1_A  BI  = M_F_CPU0_SA_DQ<1>
  10  VSS2  POWER  = GND
  11  DQS0_A_T  BI  = M_F_CPU0_SA_DQS_DP<0>
  12  DQS0_A_C  BI  = M_F_CPU0_SA_DQS_DN<0>
  13  VSS3  POWER  = GND
  14  DQ4_A  BI  = M_F_CPU0_SA_DQ<4>
  15  VSS4  POWER  = GND
  16  DQ5_A  BI  = M_F_CPU0_SA_DQ<5>
  17  VSS5  POWER  = GND
  18  DQ8_A  BI  = M_F_CPU0_SA_DQ<8>
  19  VSS6  POWER  = GND
  20  DQ9_A  BI  = M_F_CPU0_SA_DQ<9>
  21  VSS7  POWER  = GND
  22  DQS1_A_T  BI  = M_F_CPU0_SA_DQS_DP<1>
  23  DQS1_A_C  BI  = M_F_CPU0_SA_DQS_DN<1>
  24  VSS8  POWER  = GND
  25  DQ12_A  BI  = M_F_CPU0_SA_DQ<12>
  26  VSS9  POWER  = GND
  27  DQ13_A  BI  = M_F_CPU0_SA_DQ<13>
  28  VSS10  POWER  = GND
  29  DQ16_A  BI  = M_F_CPU0_SA_DQ<16>
  30  VSS11  POWER  = GND
  31  DQ17_A  BI  = M_F_CPU0_SA_DQ<17>
  32  VSS12  POWER  = GND
  33  DQS2_A_T  BI  = M_F_CPU0_SA_DQS_DP<2>
  34  DQS2_A_C  BI  = M_F_CPU0_SA_DQS_DN<2>
  35  VSS13  POWER  = GND
  36  DQ20_A  BI  = M_F_CPU0_SA_DQ<20>
  37  VSS14  POWER  = GND
  38  DQ21_A  BI  = M_F_CPU0_SA_DQ<21>
  39  VSS15  POWER  = GND
  40  DQ24_A  BI  = M_F_CPU0_SA_DQ<24>
  41  VSS16  POWER  = GND
  42  DQ25_A  BI  = M_F_CPU0_SA_DQ<25>
  43  VSS17  POWER  = GND
  44  DQS3_A_T  BI  = M_F_CPU0_SA_DQS_DP<3>
  45  DQS3_A_C  BI  = M_F_CPU0_SA_DQS_DN<3>
  46  VSS18  POWER  = GND
  47  DQ28_A  BI  = M_F_CPU0_SA_DQ<28>
  48  VSS19  POWER  = GND
  49  DQ29_A  BI  = M_F_CPU0_SA_DQ<29>
  50  VSS20  POWER  = GND
  51  CB0_A  BI  = M_F_CPU0_SA_CB<0>
  52  VSS21  POWER  = GND
  53  CB1_A  BI  = M_F_CPU0_SA_CB<1>
  54  VSS22  POWER  = GND
  55  DQS4_A_T  BI  = M_F_CPU0_SA_DQS_DP<4>
  56  DQS4_A_C  BI  = M_F_CPU0_SA_DQS_DN<4>
  57  VSS23  POWER  = GND
  58  CB4_A  BI  = M_F_CPU0_SA_CB<4>
  59  VSS24  POWER  = GND
  60  CB5_A  BI  = M_F_CPU0_SA_CB<5>
  61  VSS25  POWER  = GND
  62  ALERT_N  OUT  = M_F_CPU0_ALERT_N
  63  VSS26  POWER  = GND
  64  CS0_A_N  IN  = M_F_CPU0_SA_CS_N<0>
  65  VSS27  POWER  = GND
  66  CA0_A  IN  = M_F_CPU0_SA_CA<0>
  67  VSS28  POWER  = GND
  68  CA2_A  IN  = M_F_CPU0_SA_CA<2>
  69  VSS29  POWER  = GND
  70  CA4_A  IN  = M_F_CPU0_SA_CA<4>
  71  VSS30  POWER  = GND
  72  CA6_A  IN  = M_F_CPU0_SA_CA<6>
  73  VSS31  POWER  = GND
  74  PAR_A  IN  = M_F_CPU0_SA_PAR
  75  VSS32  POWER  = GND
  76  CA0_B  IN  = M_F_CPU0_SB_CA<0>
  77  VSS33  POWER  = GND
  78  CA2_B  IN  = M_F_CPU0_SB_CA<2>
  79  VSS34  POWER  = GND
  80  CA4_B  IN  = M_F_CPU0_SB_CA<4>
  81  VSS35  POWER  = GND
  82  CA6_B  IN  = M_F_CPU0_SB_CA<6>
  83  VSS36  POWER  = GND
  84  CS0_B_N  IN  = M_F_CPU0_SB_CS_N<0>
  85  VSS37  POWER  = GND
  86  \lbd||rsp_a_n\  OUT  = M_F_CPU0_SA_RSP<0>
  87  \lbs||rsp_b_n\  OUT  = M_F_CPU0_SB_RSP<0>
  88  VSS38  POWER  = GND
  89  CB4_B  BI  = M_F_CPU0_SB_CB<4>
  90  VSS39  POWER  = GND
  91  CB5_B  BI  = M_F_CPU0_SB_CB<5>
  92  VSS40  POWER  = GND
  93  \dqs9_b_t||tdqs9_b_t||dbi4_b_n\  BI  = M_F_CPU0_SB_DQS_DP<9>
  94  \dqs9_b_c||tdqs9_b_c\  BI  = M_F_CPU0_SB_DQS_DN<9>
  95  VSS41  POWER  = GND
  96  CB0_B  BI  = M_F_CPU0_SB_CB<0>
  97  VSS42  POWER  = GND
  98  CB1_B  BI  = M_F_CPU0_SB_CB<1>
  99  VSS43  POWER  = GND
  100  DQ0_B  BI  = M_F_CPU0_SB_DQ<0>
  101  VSS44  POWER  = GND
  102  DQ1_B  BI  = M_F_CPU0_SB_DQ<1>
  103  VSS45  POWER  = GND
  104  DQS0_B_T  BI  = M_F_CPU0_SB_DQS_DP<0>
  105  DQS0_B_C  BI  = M_F_CPU0_SB_DQS_DN<0>
  106  VSS46  POWER  = GND
  107  DQ4_B  BI  = M_F_CPU0_SB_DQ<4>
  108  VSS47  POWER  = GND
  109  DQ5_B  BI  = M_F_CPU0_SB_DQ<5>
  110  VSS48  POWER  = GND
  111  DQ8_B  BI  = M_F_CPU0_SB_DQ<8>
  112  VSS49  POWER  = GND
  113  DQ9_B  BI  = M_F_CPU0_SB_DQ<9>
  114  VSS50  POWER  = GND
  115  DQS1_B_T  BI  = M_F_CPU0_SB_DQS_DP<1>
  116  DQS1_B_C  BI  = M_F_CPU0_SB_DQS_DN<1>
  117  VSS51  POWER  = GND
  118  DQ12_B  BI  = M_F_CPU0_SB_DQ<12>
  119  VSS52  POWER  = GND
  120  DQ13_B  BI  = M_F_CPU0_SB_DQ<13>
  121  VSS53  POWER  = GND
  122  DQ16_B  BI  = M_F_CPU0_SB_DQ<16>
  123  VSS54  POWER  = GND
  124  DQ17_B  BI  = M_F_CPU0_SB_DQ<17>
  125  VSS55  POWER  = GND
  126  DQS2_B_T  BI  = M_F_CPU0_SB_DQS_DP<2>
  127  DQS2_B_C  BI  = M_F_CPU0_SB_DQS_DN<2>
  128  VSS56  POWER  = GND
  129  DQ20_B  BI  = M_F_CPU0_SB_DQ<20>
  130  VSS57  POWER  = GND
  131  DQ21_B  BI  = M_F_CPU0_SB_DQ<21>
  132  VSS58  POWER  = GND
  133  DQ24_B  BI  = M_F_CPU0_SB_DQ<24>
  134  VSS59  POWER  = GND
  135  DQ25_B  BI  = M_F_CPU0_SB_DQ<25>
  136  VSS60  POWER  = GND
  137  DQS3_B_T  BI  = M_F_CPU0_SB_DQS_DP<3>
  138  DQS3_B_C  BI  = M_F_CPU0_SB_DQS_DN<3>
  139  VSS61  POWER  = GND
  140  DQ28_B  BI  = M_F_CPU0_SB_DQ<28>
  141  VSS62  POWER  = GND
  142  DQ29_B  BI  = M_F_CPU0_SB_DQ<29>
  143  VSS63  POWER  = GND
  144  RFU1  TRI  = NC
  145  VIN_BULK1  POWER  = P12V_MEM_CPU0
  146  VIN_BULK2  POWER  = P12V_MEM_CPU0
  147  \pwr_good||fail_n\  BI  = PWRGD_CHF_CPU0_DIMM
  148  HAS  IN  = PD_CHF_CPU0_DIMM_SAA
  149  RFU2  TRI  = NC
  150  RFU3  TRI  = NC
  151  VSS64  POWER  = GND
  152  DQ2_A  BI  = M_F_CPU0_SA_DQ<2>
  153  VSS65  POWER  = GND
  154  DQ3_A  BI  = M_F_CPU0_SA_DQ<3>
  155  VSS66  POWER  = GND
  156  \dqs5_a_c||tdqs5_a_c||dqs5_a_t||tdqs5_a_t\  BI  = M_F_CPU0_SA_DQS_DN<5>
  157  \dqs5_a_t||tdqs5_a_t\  BI  = M_F_CPU0_SA_DQS_DP<5>
  158  VSS67  POWER  = GND
  159  DQ6_A  BI  = M_F_CPU0_SA_DQ<6>
  160  VSS68  POWER  = GND
  161  DQ7_A  BI  = M_F_CPU0_SA_DQ<7>
  162  VSS69  POWER  = GND
  163  DQ10_A  BI  = M_F_CPU0_SA_DQ<10>
  164  VSS70  POWER  = GND
  165  DQ11_A  BI  = M_F_CPU0_SA_DQ<11>
  166  VSS71  POWER  = GND
  167  \dqs6_a_c||tdqs6_a_c||dqs6_a_t||tdqs6_a_t\  BI  = M_F_CPU0_SA_DQS_DN<6>
  168  \dqs6_a_t||tdqs6_a_t\  BI  = M_F_CPU0_SA_DQS_DP<6>
  169  VSS72  POWER  = GND
  170  DQ14_A  BI  = M_F_CPU0_SA_DQ<14>
  171  VSS73  POWER  = GND
  172  DQ15_A  BI  = M_F_CPU0_SA_DQ<15>
  173  VSS74  POWER  = GND
  174  DQ18_A  BI  = M_F_CPU0_SA_DQ<18>
  175  VSS75  POWER  = GND
  176  DQ19_A  BI  = M_F_CPU0_SA_DQ<19>
  177  VSS76  POWER  = GND
  178  \dqs7_a_c||tdqs7_a_c\  BI  = M_F_CPU0_SA_DQS_DN<7>
  179  \dqs7_a_t||tdqs7_a_t\  BI  = M_F_CPU0_SA_DQS_DP<7>
  180  VSS77  POWER  = GND
  181  DQ22_A  BI  = M_F_CPU0_SA_DQ<22>
  182  VSS78  POWER  = GND
  183  DQ23_A  BI  = M_F_CPU0_SA_DQ<23>
  184  VSS79  POWER  = GND
  185  DQ26_A  BI  = M_F_CPU0_SA_DQ<26>
  186  VSS80  POWER  = GND
  187  DQ27_A  BI  = M_F_CPU0_SA_DQ<27>
  188  VSS81  POWER  = GND
  189  \dqs8_a_c||tdqs8_a_c\  BI  = M_F_CPU0_SA_DQS_DN<8>
  190  \dqs8_a_t||tdqs8_a_t\  BI  = M_F_CPU0_SA_DQS_DP<8>
  191  VSS82  POWER  = GND
  192  DQ30_A  BI  = M_F_CPU0_SA_DQ<30>
  193  VSS83  POWER  = GND
  194  DQ31_A  BI  = M_F_CPU0_SA_DQ<31>
  195  VSS84  POWER  = GND
  196  CB2_A  BI  = M_F_CPU0_SA_CB<2>
  197  VSS85  POWER  = GND
  198  CB3_A  BI  = M_F_CPU0_SA_CB<3>
  199  VSS86  POWER  = GND
  200  \dqs9_a_c||tdqs9_a_c\  BI  = M_F_CPU0_SA_DQS_DN<9>
  201  \dqs9_a_t||tdqs9_a_t\  BI  = M_F_CPU0_SA_DQS_DP<9>
  202  VSS87  POWER  = GND
  203  CB6_A  BI  = M_F_CPU0_SA_CB<6>
  204  VSS88  POWER  = GND
  205  CB7_A  BI  = M_F_CPU0_SA_CB<7>
  206  VSS89  POWER  = GND
  207  RESET_N  IN  = M_F_CPU0_RESET_N
  208  VSS90  POWER  = GND
  209  CS1_A_N  IN  = M_F_CPU0_SA_CS_N<1>
  210  VSS91  POWER  = GND
  211  CA1_A  IN  = M_F_CPU0_SA_CA<1>
  212  VSS92  POWER  = GND
  213  CA3_A  IN  = M_F_CPU0_SA_CA<3>
  214  VSS93  POWER  = GND
  215  CA5_A  IN  = M_F_CPU0_SA_CA<5>
  216  VSS94  POWER  = GND
  217  CK_T  IN  = M_F_CPU0_CLK_DP<0>
  218  CK_C  IN  = M_F_CPU0_CLK_DN<0>
  219  VSS95  POWER  = GND
  220  RFU4  TRI  = NC
  221  CA1_B  IN  = M_F_CPU0_SB_CA<1>
  222  VSS96  POWER  = GND
  223  CA3_B  IN  = M_F_CPU0_SB_CA<3>
  224  VSS97  POWER  = GND
  225  CA5_B  IN  = M_F_CPU0_SB_CA<5>
  226  VSS98  POWER  = GND
  227  PAR_B  IN  = M_F_CPU0_SB_PAR
  228  VSS99  POWER  = GND
  229  CS1_B_N  IN  = M_F_CPU0_SB_CS_N<1>
  230  VSS100  POWER  = GND
  231  RFU5  TRI  = NC
  232  RFU6  TRI  = NC
  233  VSS101  POWER  = GND
  234  CB6_B  BI  = M_F_CPU0_SB_CB<6>
  235  VSS102  POWER  = GND
  236  CB7_B  BI  = M_F_CPU0_SB_CB<7>
  237  VSS103  POWER  = GND
  238  DQS4_B_C  BI  = M_F_CPU0_SB_DQS_DN<4>
  239  DQS4_B_T  BI  = M_F_CPU0_SB_DQS_DP<4>
  240  VSS104  POWER  = GND
  241  CB2_B  BI  = M_F_CPU0_SB_CB<2>
  242  VSS105  POWER  = GND
  243  CB3_B  BI  = M_F_CPU0_SB_CB<3>
  244  VSS106  POWER  = GND
  245  DQ2_B  BI  = M_F_CPU0_SB_DQ<2>
  246  VSS107  POWER  = GND
  247  DQ3_B  BI  = M_F_CPU0_SB_DQ<3>
  248  VSS108  POWER  = GND
  249  \dqs5_b_c||tdqs5_b_c\  BI  = M_F_CPU0_SB_DQS_DN<5>
  250  \dqs5_b_t||tdqs5_b_t\  BI  = M_F_CPU0_SB_DQS_DP<5>
  251  VSS109  POWER  = GND
  252  DQ6_B  BI  = M_F_CPU0_SB_DQ<6>
  253  VSS110  POWER  = GND
  254  DQ7_B  BI  = M_F_CPU0_SB_DQ<7>
  255  VSS111  POWER  = GND
  256  DQ10_B  BI  = M_F_CPU0_SB_DQ<10>
  257  VSS112  POWER  = GND
  258  DQ11_B  BI  = M_F_CPU0_SB_DQ<11>
  259  VSS113  POWER  = GND
  260  \dqs6_b_c||tdqs6_b_c\  BI  = M_F_CPU0_SB_DQS_DN<6>
  261  \dqs6_b_t||tdqs6_b_t\  BI  = M_F_CPU0_SB_DQS_DP<6>
  262  VSS114  POWER  = GND
  263  DQ14_B  BI  = M_F_CPU0_SB_DQ<14>
  264  VSS115  POWER  = GND
  265  DQ15_B  BI  = M_F_CPU0_SB_DQ<15>
  266  VSS116  POWER  = GND
  267  DQ18_B  BI  = M_F_CPU0_SB_DQ<18>
  268  VSS117  POWER  = GND
  269  DQ19_B  BI  = M_F_CPU0_SB_DQ<19>
  270  VSS118  POWER  = GND
  271  \dqs7_b_c||tdqs7_b_c\  BI  = M_F_CPU0_SB_DQS_DN<7>
  272  \dqs7_b_t||tdqs7_b_t\  BI  = M_F_CPU0_SB_DQS_DP<7>
  273  VSS119  POWER  = GND
  274  DQ22_B  BI  = M_F_CPU0_SB_DQ<22>
  275  VSS120  POWER  = GND
  276  DQ23_B  BI  = M_F_CPU0_SB_DQ<23>
  277  VSS121  POWER  = GND
  278  DQ26_B  BI  = M_F_CPU0_SB_DQ<26>
  279  VSS122  POWER  = GND
  280  DQ27_B  BI  = M_F_CPU0_SB_DQ<27>
  281  VSS123  POWER  = GND
  282  \dqs8_b_c||tdqs8_b_c\  BI  = M_F_CPU0_SB_DQS_DN<8>
  283  \dqs8_b_t||tdqs8_b_t\  BI  = M_F_CPU0_SB_DQS_DP<8>
  284  VSS124  POWER  = GND
  285  DQ30_B  BI  = M_F_CPU0_SB_DQ<30>
  286  VSS125  POWER  = GND
  287  DQ31_B  BI  = M_F_CPU0_SB_DQ<31>
  288  VSS126  POWER  = GND
  G1  G1  POWER  = GND
  G2  G2  POWER  = GND
  G3  G3  POWER  = GND
